# S9S_MB_2U (Grand Teton) — schematic netlist excerpt (pin names and nets, part order shuffled) for the footprints in the layout excerpt that follows; sources: Cadence DE-HDL packaged netlist, KiCad conversion of 03242023_DA0F0TMBIJ0_F0T_Motherboard_J_brd_V01_OCP.brd

J8  SCONN288_ADR50017P087CC  SCONN288_ADR50017-P087CC IO  pkg DDR288S_1-1VXB  page 89
  VIN_BULK0  = P12V_S3_AUX_CPU0_NVDIMM
  RFU0  = TP_CHD_CPU0_DIMM2_FRU_0
  VIN_MGMT  = P3V3_AUX
  HSCL  = I3C_SPD_DDRABCD_CPU0_LVC1_SCL_7
  HSDA  = I3C_SPD_DDRABCD_CPU0_LVC1_SDA
  VSS0  = GND
  DQ0_A  = M_D_CPU0_SA_DQ<0>
  VSS1  = GND
  DQ1_A  = M_D_CPU0_SA_DQ<1>
  VSS2  = GND
  DQS0_A_T  = M_D_CPU0_SA_DQS_DP<0>
  DQS0_A_C  = M_D_CPU0_SA_DQS_DN<0>
  VSS3  = GND
  DQ4_A  = M_D_CPU0_SA_DQ<4>
  VSS4  = GND
  DQ5_A  = M_D_CPU0_SA_DQ<5>
  VSS5  = GND
  DQ8_A  = M_D_CPU0_SA_DQ<8>
  VSS6  = GND
  DQ9_A  = M_D_CPU0_SA_DQ<9>
  VSS7  = GND
  DQS1_A_T  = M_D_CPU0_SA_DQS_DP<1>
  DQS1_A_C  = M_D_CPU0_SA_DQS_DN<1>
  VSS8  = GND
  DQ12_A  = M_D_CPU0_SA_DQ<12>
  VSS9  = GND
  DQ13_A  = M_D_CPU0_SA_DQ<13>
  VSS10  = GND
  DQ16_A  = M_D_CPU0_SA_DQ<16>
  VSS11  = GND
  DQ17_A  = M_D_CPU0_SA_DQ<17>
  VSS12  = GND
  DQS2_A_T  = M_D_CPU0_SA_DQS_DP<2>
  DQS2_A_C  = M_D_CPU0_SA_DQS_DN<2>
  VSS13  = GND
  DQ20_A  = M_D_CPU0_SA_DQ<20>
  VSS14  = GND
  DQ21_A  = M_D_CPU0_SA_DQ<21>
  VSS15  = GND
  DQ24_A  = M_D_CPU0_SA_DQ<24>
  VSS16  = GND
  DQ25_A  = M_D_CPU0_SA_DQ<25>
  VSS17  = GND
  DQS3_A_T  = M_D_CPU0_SA_DQS_DP<3>
  DQS3_A_C  = M_D_CPU0_SA_DQS_DN<3>
  VSS18  = GND
  DQ28_A  = M_D_CPU0_SA_DQ<28>
  VSS19  = GND
  DQ29_A  = M_D_CPU0_SA_DQ<29>
  VSS20  = GND
  CB0_A  = M_D_CPU0_SA_CB<0>
  VSS21  = GND
  CB1_A  = M_D_CPU0_SA_CB<1>
  VSS22  = GND
  DQS4_A_T  = M_D_CPU0_SA_DQS_DP<4>
  DQS4_A_C  = M_D_CPU0_SA_DQS_DN<4>
  VSS23  = GND
  CB4_A  = M_D_CPU0_SA_CB<4>
  VSS24  = GND
  CB5_A  = M_D_CPU0_SA_CB<5>
  VSS25  = GND
  ALERT_N  = M_D_CPU0_ALERT_N
  VSS26  = GND
  CS0_A_N  = M_D_CPU0_SA_CS_N<2>
  VSS27  = GND
  CA0_A  = M_D_CPU0_SA_CA<0>
  VSS28  = GND
  CA2_A  = M_D_CPU0_SA_CA<2>
  VSS29  = GND
  CA4_A  = M_D_CPU0_SA_CA<4>
  VSS30  = GND
  CA6_A  = M_D_CPU0_SA_CA<6>
  VSS31  = GND
  PAR_A  = M_D_CPU0_SA_PAR
  VSS32  = GND
  CA0_B  = M_D_CPU0_SB_CA<0>
  VSS33  = GND
  CA2_B  = M_D_CPU0_SB_CA<2>
  VSS34  = GND
  CA4_B  = M_D_CPU0_SB_CA<4>
  VSS35  = GND
  CA6_B  = M_D_CPU0_SB_CA<6>
  VSS36  = GND
  CS0_B_N  = M_D_CPU0_SB_CS_N<2>
  VSS37  = GND
  \lbd||rsp_a_n\  = M_D_CPU0_SA_RSP<1>
  \lbs||rsp_b_n\  = M_D_CPU0_SB_RSP<1>
  VSS38  = GND
  CB4_B  = M_D_CPU0_SB_CB<4>
  VSS39  = GND
  CB5_B  = M_D_CPU0_SB_CB<5>
  VSS40  = GND
  \dqs9_b_t||tdqs9_b_t||dbi4_b_n\  = M_D_CPU0_SB_DQS_DP<9>
  \dqs9_b_c||tdqs9_b_c\  = M_D_CPU0_SB_DQS_DN<9>
  VSS41  = GND
  CB0_B  = M_D_CPU0_SB_CB<0>
  VSS42  = GND
  CB1_B  = M_D_CPU0_SB_CB<1>
  VSS43  = GND
  DQ0_B  = M_D_CPU0_SB_DQ<0>
  VSS44  = GND
  DQ1_B  = M_D_CPU0_SB_DQ<1>
  VSS45  = GND
  DQS0_B_T  = M_D_CPU0_SB_DQS_DP<0>
  DQS0_B_C  = M_D_CPU0_SB_DQS_DN<0>
  VSS46  = GND
  DQ4_B  = M_D_CPU0_SB_DQ<4>
  VSS47  = GND
  DQ5_B  = M_D_CPU0_SB_DQ<5>
  VSS48  = GND
  DQ8_B  = M_D_CPU0_SB_DQ<8>
  VSS49  = GND
  DQ9_B  = M_D_CPU0_SB_DQ<9>
  VSS50  = GND
  DQS1_B_T  = M_D_CPU0_SB_DQS_DP<1>
  DQS1_B_C  = M_D_CPU0_SB_DQS_DN<1>
  VSS51  = GND
  DQ12_B  = M_D_CPU0_SB_DQ<12>
  VSS52  = GND
  DQ13_B  = M_D_CPU0_SB_DQ<13>
  VSS53  = GND
  DQ16_B  = M_D_CPU0_SB_DQ<16>
  VSS54  = GND
  DQ17_B  = M_D_CPU0_SB_DQ<17>
  VSS55  = GND
  DQS2_B_T  = M_D_CPU0_SB_DQS_DP<2>
  DQS2_B_C  = M_D_CPU0_SB_DQS_DN<2>
  VSS56  = GND
  DQ20_B  = M_D_CPU0_SB_DQ<20>
  VSS57  = GND
  DQ21_B  = M_D_CPU0_SB_DQ<21>
  VSS58  = GND
  DQ24_B  = M_D_CPU0_SB_DQ<24>
  VSS59  = GND
  DQ25_B  = M_D_CPU0_SB_DQ<25>
  VSS60  = GND
  DQS3_B_T  = M_D_CPU0_SB_DQS_DP<3>
  DQS3_B_C  = M_D_CPU0_SB_DQS_DN<3>
  VSS61  = GND
  DQ28_B  = M_D_CPU0_SB_DQ<28>
  VSS62  = GND
  DQ29_B  = M_D_CPU0_SB_DQ<29>
  VSS63  = GND
  RFU1  = TP_CHD_CPU0_DIMM2_FRU_1
  VIN_BULK1  = P12V_S3_AUX_CPU0_NVDIMM
  VIN_BULK2  = P12V_S3_AUX_CPU0_NVDIMM
  \pwr_good||fail_n\  = PWRGD_CHD_CPU0_DIMM2
  HSA  = PD_CHD_CPU0_DIMM2_SAA
  RFU2  = TP_CHD_CPU0_DIMM2_FRU_2
  RFU3  = TP_CHD_CPU0_DIMM2_FRU_3
  VSS64  = GND
  DQ2_A  = M_D_CPU0_SA_DQ<2>
  VSS65  = GND
  DQ3_A  = M_D_CPU0_SA_DQ<3>
  VSS66  = GND
  \dqs5_a_c||tdqs5_a_c||dqs5_a_t||tdqs5_a_t\  = M_D_CPU0_SA_DQS_DN<5>
  \dqs5_a_t||tdqs5_a_t\  = M_D_CPU0_SA_DQS_DP<5>
  VSS67  = GND
  DQ6_A  = M_D_CPU0_SA_DQ<6>
  VSS68  = GND
  DQ7_A  = M_D_CPU0_SA_DQ<7>
  VSS69  = GND
  DQ10_A  = M_D_CPU0_SA_DQ<10>
  VSS70  = GND
  DQ11_A  = M_D_CPU0_SA_DQ<11>
  VSS71  = GND
  \dqs6_a_c||tdqs6_a_c||dqs6_a_t||tdqs6_a_t\  = M_D_CPU0_SA_DQS_DN<6>
  \dqs6_a_t||tdqs6_a_t\  = M_D_CPU0_SA_DQS_DP<6>
  VSS72  = GND
  DQ14_A  = M_D_CPU0_SA_DQ<14>
  VSS73  = GND
  DQ15_A  = M_D_CPU0_SA_DQ<15>
  VSS74  = GND
  DQ18_A  = M_D_CPU0_SA_DQ<18>
  VSS75  = GND
  DQ19_A  = M_D_CPU0_SA_DQ<19>
  VSS76  = GND
  \dqs7_a_c||tdqs7_a_c\  = M_D_CPU0_SA_DQS_DN<7>
  \dqs7_a_t||tdqs7_a_t\  = M_D_CPU0_SA_DQS_DP<7>
  VSS77  = GND
  DQ22_A  = M_D_CPU0_SA_DQ<22>
  VSS78  = GND
  DQ23_A  = M_D_CPU0_SA_DQ<23>
  VSS79  = GND
  DQ26_A  = M_D_CPU0_SA_DQ<26>
  VSS80  = GND
  DQ27_A  = M_D_CPU0_SA_DQ<27>
  VSS81  = GND
  \dqs8_a_c||tdqs8_a_c\  = M_D_CPU0_SA_DQS_DN<8>
  \dqs8_a_t||tdqs8_a_t\  = M_D_CPU0_SA_DQS_DP<8>
  VSS82  = GND
  DQ30_A  = M_D_CPU0_SA_DQ<30>
  VSS83  = GND
  DQ31_A  = M_D_CPU0_SA_DQ<31>
  VSS84  = GND
  CB2_A  = M_D_CPU0_SA_CB<2>
  VSS85  = GND
  CB3_A  = M_D_CPU0_SA_CB<3>
  VSS86  = GND
  \dqs9_a_c||tdqs9_a_c\  = M_D_CPU0_SA_DQS_DN<9>
  \dqs9_a_t||tdqs9_a_t\  = M_D_CPU0_SA_DQS_DP<9>
  VSS87  = GND
  CB6_A  = M_D_CPU0_SA_CB<6>
  VSS88  = GND
  CB7_A  = M_D_CPU0_SA_CB<7>
  VSS89  = GND
  RESET_N  = RST_M_CD_CPU0_FPGA_N
  VSS90  = GND
  CS1_A_N  = M_D_CPU0_SA_CS_N<3>
  VSS91  = GND
  CA1_A  = M_D_CPU0_SA_CA<1>
  VSS92  = GND
  CA3_A  = M_D_CPU0_SA_CA<3>
  VSS93  = GND
  CA5_A  = M_D_CPU0_SA_CA<5>
  VSS94  = GND
  CK_T  = M_D_CPU0_CLK_DP<1>
  CK_C  = M_D_CPU0_CLK_DN<1>
  VSS95  = GND
  RFU4  = TP_CHD_CPU0_DIMM2_FRU_4
  CA1_B  = M_D_CPU0_SB_CA<1>
  VSS96  = GND
  CA3_B  = M_D_CPU0_SB_CA<3>
  VSS97  = GND
  CA5_B  = M_D_CPU0_SB_CA<5>
  VSS98  = GND
  PAR_B  = M_D_CPU0_SB_PAR
  VSS99  = GND
  CS1_B_N  = M_D_CPU0_SB_CS_N<3>
  VSS100  = GND
  RFU5  = TP_CHD_CPU0_DIMM2_FRU_5
  RFU6  = TP_CHD_CPU0_DIMM2_FRU_6
  VSS101  = GND
  CB6_B  = M_D_CPU0_SB_CB<6>
  VSS102  = GND
  CB7_B  = M_D_CPU0_SB_CB<7>
  VSS103  = GND
  DQS4_B_C  = M_D_CPU0_SB_DQS_DN<4>
  DQS4_B_T  = M_D_CPU0_SB_DQS_DP<4>
  VSS104  = GND
  CB2_B  = M_D_CPU0_SB_CB<2>
  VSS105  = GND
  CB3_B  = M_D_CPU0_SB_CB<3>
  VSS106  = GND
  DQ2_B  = M_D_CPU0_SB_DQ<2>
  VSS107  = GND
  DQ3_B  = M_D_CPU0_SB_DQ<3>
  VSS108  = GND
  \dqs5_b_c||tdqs5_b_c\  = M_D_CPU0_SB_DQS_DN<5>
  \dqs5_b_t||tdqs5_b_t\  = M_D_CPU0_SB_DQS_DP<5>
  VSS109  = GND
  DQ6_B  = M_D_CPU0_SB_DQ<6>
  VSS110  = GND
  DQ7_B  = M_D_CPU0_SB_DQ<7>
  VSS111  = GND
  DQ10_B  = M_D_CPU0_SB_DQ<10>
  VSS112  = GND
  DQ11_B  = M_D_CPU0_SB_DQ<11>
  VSS113  = GND
  \dqs6_b_c||tdqs6_b_c\  = M_D_CPU0_SB_DQS_DN<6>
  \dqs6_b_t||tdqs6_b_t\  = M_D_CPU0_SB_DQS_DP<6>
  VSS114  = GND
  DQ14_B  = M_D_CPU0_SB_DQ<14>
  VSS115  = GND
  DQ15_B  = M_D_CPU0_SB_DQ<15>
  VSS116  = GND
  DQ18_B  = M_D_CPU0_SB_DQ<18>
  VSS117  = GND
  DQ19_B  = M_D_CPU0_SB_DQ<19>
  VSS118  = GND
  \dqs7_b_c||tdqs7_b_c\  = M_D_CPU0_SB_DQS_DN<7>
  \dqs7_b_t||tdqs7_b_t\  = M_D_CPU0_SB_DQS_DP<7>
  VSS119  = GND
  DQ22_B  = M_D_CPU0_SB_DQ<22>
  VSS120  = GND
  DQ23_B  = M_D_CPU0_SB_DQ<23>
  VSS121  = GND
  DQ26_B  = M_D_CPU0_SB_DQ<26>
  VSS122  = GND
  DQ27_B  = M_D_CPU0_SB_DQ<27>
  VSS123  = GND
  \dqs8_b_c||tdqs8_b_c\  = M_D_CPU0_SB_DQS_DN<8>
  \dqs8_b_t||tdqs8_b_t\  = M_D_CPU0_SB_DQS_DP<8>
  VSS124  = GND
  DQ30_B  = M_D_CPU0_SB_DQ<30>
  VSS125  = GND
  DQ31_B  = M_D_CPU0_SB_DQ<31>
  VSS126  = GND
  G1  = GND
  G2  = GND
  G3  = GND

(kicad_pcb
	(version 20260206)
	(generator "pcbnew")
	(generator_version "10.0")
	(general
		(thickness 1.6)
		(legacy_teardrops no)
	)
	(paper "A4")
	(title_block
		(title "03242023_DA0F0TMBIJ0_F0T_Motherboard_J_brd_V01_OCP.brd")
		(comment 1 "Grand Teton / footprint 652 of 6105 (J8), pads 138-182 of 291")
	)
	(layers
		(0 "F.Cu" signal "TOP")
		(4 "In1.Cu" signal "GND")
		(6 "In2.Cu" signal "IN1")
		(8 "In3.Cu" signal "GND1")
		(10 "In4.Cu" signal "IN2")
		(12 "In5.Cu" signal "GND2")
		(14 "In6.Cu" signal "IN3")
		(16 "In7.Cu" signal "GND3")
		(18 "In8.Cu" signal "VCC")
		(20 "In9.Cu" signal "VCC1")
		(22 "In10.Cu" signal "GND4")
		(24 "In11.Cu" signal "IN4")
		(26 "In12.Cu" signal "GND5")
		(28 "In13.Cu" signal "IN5")
		(30 "In14.Cu" signal "GND6")
		(32 "In15.Cu" signal "IN6")
		(34 "In16.Cu" signal "GND7")
		(2 "B.Cu" signal "BOTTOM")
		(9 "F.Adhes" user "F.Adhesive")
		(11 "B.Adhes" user "B.Adhesive")
		(13 "F.Paste" user "Package Geometry/Pastemask Top")
		(15 "B.Paste" user "Package Geometry/Pastemask Bottom")
		(5 "F.SilkS" user "Ref Des/Silkscreen Top")
		(7 "B.SilkS" user "Ref Des/Silkscreen Bottom")
		(1 "F.Mask" user "Board Geometry/Soldermask Top")
		(3 "B.Mask" user "Board Geometry/Soldermask Bottom")
		(17 "Dwgs.User" user "User.Drawings")
		(19 "Cmts.User" user "User.Comments")
		(21 "Eco1.User" user "User.Eco1")
		(23 "Eco2.User" user "User.Eco2")
		(25 "Edge.Cuts" user "Board Geometry/Outline")
		(27 "Margin" user)
		(31 "F.CrtYd" user "Package Geometry/Place Bound Top")
		(29 "B.CrtYd" user "Package Geometry/Place Bound Bottom")
		(35 "F.Fab" user "Ref Des/Assembly Top")
		(33 "B.Fab" user "Ref Des/Assembly Bottom")
	)
	(footprint ""
		(layer "F.Cu")
		(at 265.674348 -258.091686)
		(property "Reference" "J8"
			(at -3.683 -81.702148 0)
			(unlocked yes)
			(layer "F.SilkS")
			(effects
				(font
					(size 0.7874 0.5842)
					(thickness 0.1524)
				)
				(justify left)
			)
		)
		(property "Value" ""
			(at 0 0 0)
			(layer "F.Fab")
			(effects
				(font
					(size 1.27 1.27)
				)
			)
		)
		(duplicate_pad_numbers_are_jumpers no)
		(pad "138" smd rect
			(at -2.050034 58.224928 270)
			(size 0.519938 1.4986)
			(layers "F.Cu" "F.Mask" "F.Paste")
			(net "M_D_CPU0_SB_DQS_DN<3>")
		)
		(pad "139" smd rect
			(at -2.050034 59.075066 270)
			(size 0.519938 1.4986)
			(layers "F.Cu" "F.Mask" "F.Paste")
			(net "GND")
		)
		(pad "140" smd rect
			(at -2.050034 59.92495 270)
			(size 0.519938 1.4986)
			(layers "F.Cu" "F.Mask" "F.Paste")
			(net "M_D_CPU0_SB_DQ<28>")
		)
		(pad "141" smd rect
			(at -2.050034 60.775088 270)
			(size 0.519938 1.4986)
			(layers "F.Cu" "F.Mask" "F.Paste")
			(net "GND")
		)
		(pad "142" smd rect
			(at -2.050034 61.624972 270)
			(size 0.519938 1.4986)
			(layers "F.Cu" "F.Mask" "F.Paste")
			(net "M_D_CPU0_SB_DQ<29>")
		)
		(pad "143" smd rect
			(at -2.050034 62.47511 270)
			(size 0.519938 1.4986)
			(layers "F.Cu" "F.Mask" "F.Paste")
			(net "GND")
		)
		(pad "144" smd rect
			(at -2.050034 63.324994 270)
			(size 0.519938 1.4986)
			(layers "F.Cu" "F.Mask" "F.Paste")
			(net "TP_CHD_CPU0_DIMM2_FRU_1")
		)
		(pad "145" smd rect
			(at 2.050034 -63.324994 270)
			(size 0.519938 1.4986)
			(layers "F.Cu" "F.Mask" "F.Paste")
			(net "P12V_S3_AUX_CPU0_NVDIMM")
		)
		(pad "146" smd rect
			(at 2.050034 -62.47511 270)
			(size 0.519938 1.4986)
			(layers "F.Cu" "F.Mask" "F.Paste")
			(net "P12V_S3_AUX_CPU0_NVDIMM")
		)
		(pad "147" smd rect
			(at 2.050034 -61.624972 270)
			(size 0.519938 1.4986)
			(layers "F.Cu" "F.Mask" "F.Paste")
			(net "PWRGD_CHD_CPU0_DIMM2")
		)
		(pad "148" smd rect
			(at 2.050034 -60.775088 270)
			(size 0.519938 1.4986)
			(layers "F.Cu" "F.Mask" "F.Paste")
			(net "PD_CHD_CPU0_DIMM2_SAA")
		)
		(pad "149" smd rect
			(at 2.050034 -59.92495 270)
			(size 0.519938 1.4986)
			(layers "F.Cu" "F.Mask" "F.Paste")
			(net "TP_CHD_CPU0_DIMM2_FRU_2")
		)
		(pad "150" smd rect
			(at 2.050034 -59.075066 270)
			(size 0.519938 1.4986)
			(layers "F.Cu" "F.Mask" "F.Paste")
			(net "TP_CHD_CPU0_DIMM2_FRU_3")
		)
		(pad "151" smd rect
			(at 2.050034 -58.224928 270)
			(size 0.519938 1.4986)
			(layers "F.Cu" "F.Mask" "F.Paste")
			(net "GND")
		)
		(pad "152" smd rect
			(at 2.050034 -57.375044 270)
			(size 0.519938 1.4986)
			(layers "F.Cu" "F.Mask" "F.Paste")
			(net "M_D_CPU0_SA_DQ<2>")
		)
		(pad "153" smd rect
			(at 2.050034 -56.524906 270)
			(size 0.519938 1.4986)
			(layers "F.Cu" "F.Mask" "F.Paste")
			(net "GND")
		)
		(pad "154" smd rect
			(at 2.050034 -55.675022 270)
			(size 0.519938 1.4986)
			(layers "F.Cu" "F.Mask" "F.Paste")
			(net "M_D_CPU0_SA_DQ<3>")
		)
		(pad "155" smd rect
			(at 2.050034 -54.824884 270)
			(size 0.519938 1.4986)
			(layers "F.Cu" "F.Mask" "F.Paste")
			(net "GND")
		)
		(pad "156" smd rect
			(at 2.050034 -53.975 270)
			(size 0.519938 1.4986)
			(layers "F.Cu" "F.Mask" "F.Paste")
			(net "M_D_CPU0_SA_DQS_DN<5>")
		)
		(pad "157" smd rect
			(at 2.050034 -53.125116 270)
			(size 0.519938 1.4986)
			(layers "F.Cu" "F.Mask" "F.Paste")
			(net "M_D_CPU0_SA_DQS_DP<5>")
		)
		(pad "158" smd rect
			(at 2.050034 -52.274978 270)
			(size 0.519938 1.4986)
			(layers "F.Cu" "F.Mask" "F.Paste")
			(net "GND")
		)
		(pad "159" smd rect
			(at 2.050034 -51.425094 270)
			(size 0.519938 1.4986)
			(layers "F.Cu" "F.Mask" "F.Paste")
			(net "M_D_CPU0_SA_DQ<6>")
		)
		(pad "160" smd rect
			(at 2.050034 -50.574956 270)
			(size 0.519938 1.4986)
			(layers "F.Cu" "F.Mask" "F.Paste")
			(net "GND")
		)
		(pad "161" smd rect
			(at 2.050034 -49.725072 270)
			(size 0.519938 1.4986)
			(layers "F.Cu" "F.Mask" "F.Paste")
			(net "M_D_CPU0_SA_DQ<7>")
		)
		(pad "162" smd rect
			(at 2.050034 -48.874934 270)
			(size 0.519938 1.4986)
			(layers "F.Cu" "F.Mask" "F.Paste")
			(net "GND")
		)
		(pad "163" smd rect
			(at 2.050034 -48.02505 270)
			(size 0.519938 1.4986)
			(layers "F.Cu" "F.Mask" "F.Paste")
			(net "M_D_CPU0_SA_DQ<10>")
		)
		(pad "164" smd rect
			(at 2.050034 -47.174912 270)
			(size 0.519938 1.4986)
			(layers "F.Cu" "F.Mask" "F.Paste")
			(net "GND")
		)
		(pad "165" smd rect
			(at 2.050034 -46.325028 270)
			(size 0.519938 1.4986)
			(layers "F.Cu" "F.Mask" "F.Paste")
			(net "M_D_CPU0_SA_DQ<11>")
		)
		(pad "166" smd rect
			(at 2.050034 -45.47489 270)
			(size 0.519938 1.4986)
			(layers "F.Cu" "F.Mask" "F.Paste")
			(net "GND")
		)
		(pad "167" smd rect
			(at 2.050034 -44.625006 270)
			(size 0.519938 1.4986)
			(layers "F.Cu" "F.Mask" "F.Paste")
			(net "M_D_CPU0_SA_DQS_DN<6>")
		)
		(pad "168" smd rect
			(at 2.050034 -43.775122 270)
			(size 0.519938 1.4986)
			(layers "F.Cu" "F.Mask" "F.Paste")
			(net "M_D_CPU0_SA_DQS_DP<6>")
		)
		(pad "169" smd rect
			(at 2.050034 -42.924984 270)
			(size 0.519938 1.4986)
			(layers "F.Cu" "F.Mask" "F.Paste")
			(net "GND")
		)
		(pad "170" smd rect
			(at 2.050034 -42.0751 270)
			(size 0.519938 1.4986)
			(layers "F.Cu" "F.Mask" "F.Paste")
			(net "M_D_CPU0_SA_DQ<14>")
		)
		(pad "171" smd rect
			(at 2.050034 -41.224962 270)
			(size 0.519938 1.4986)
			(layers "F.Cu" "F.Mask" "F.Paste")
			(net "GND")
		)
		(pad "172" smd rect
			(at 2.050034 -40.375078 270)
			(size 0.519938 1.4986)
			(layers "F.Cu" "F.Mask" "F.Paste")
			(net "M_D_CPU0_SA_DQ<15>")
		)
		(pad "173" smd rect
			(at 2.050034 -39.52494 270)
			(size 0.519938 1.4986)
			(layers "F.Cu" "F.Mask" "F.Paste")
			(net "GND")
		)
		(pad "174" smd rect
			(at 2.050034 -38.675056 270)
			(size 0.519938 1.4986)
			(layers "F.Cu" "F.Mask" "F.Paste")
			(net "M_D_CPU0_SA_DQ<18>")
		)
		(pad "175" smd rect
			(at 2.050034 -37.824918 270)
			(size 0.519938 1.4986)
			(layers "F.Cu" "F.Mask" "F.Paste")
			(net "GND")
		)
		(pad "176" smd rect
			(at 2.050034 -36.975034 270)
			(size 0.519938 1.4986)
			(layers "F.Cu" "F.Mask" "F.Paste")
			(net "M_D_CPU0_SA_DQ<19>")
		)
		(pad "177" smd rect
			(at 2.050034 -36.124896 270)
			(size 0.519938 1.4986)
			(layers "F.Cu" "F.Mask" "F.Paste")
			(net "GND")
		)
		(pad "178" smd rect
			(at 2.050034 -35.275012 270)
			(size 0.519938 1.4986)
			(layers "F.Cu" "F.Mask" "F.Paste")
			(net "M_D_CPU0_SA_DQS_DN<7>")
		)
		(pad "179" smd rect
			(at 2.050034 -34.425128 270)
			(size 0.519938 1.4986)
			(layers "F.Cu" "F.Mask" "F.Paste")
			(net "M_D_CPU0_SA_DQS_DP<7>")
		)
		(pad "180" smd rect
			(at 2.050034 -33.57499 270)
			(size 0.519938 1.4986)
			(layers "F.Cu" "F.Mask" "F.Paste")
			(net "GND")
		)
		(pad "181" smd rect
			(at 2.050034 -32.725106 270)
			(size 0.519938 1.4986)
			(layers "F.Cu" "F.Mask" "F.Paste")
			(net "M_D_CPU0_SA_DQ<22>")
		)
		(pad "182" smd rect
			(at 2.050034 -31.874968 270)
			(size 0.519938 1.4986)
			(layers "F.Cu" "F.Mask" "F.Paste")
			(net "GND")
		)
	)
)
